(kicad_pcb
	(version 20260206)
	(generator "pcbnew")
	(generator_version "10.0")
	(general
		(thickness 1.6)
		(legacy_teardrops no)
	)
	(paper "A4")
	(title_block
		(title "04192023_DAF0TMB3IC0_F0TG_MB_C_brd_V02_OCP.brd")
		(comment 1 "Grand Teton / footprints 7003-7010 of 8354")
	)
	(layers
		(0 "F.Cu" signal "TOP")
		(4 "In1.Cu" signal "GND")
		(6 "In2.Cu" signal "IN1")
		(8 "In3.Cu" signal "GND1")
		(10 "In4.Cu" signal "IN2")
		(12 "In5.Cu" signal "GND2")
		(14 "In6.Cu" signal "IN3")
		(16 "In7.Cu" signal "GND3")
		(18 "In8.Cu" signal "VCC")
		(20 "In9.Cu" signal "VCC1")
		(22 "In10.Cu" signal "GND4")
		(24 "In11.Cu" signal "IN4")
		(26 "In12.Cu" signal "GND5")
		(28 "In13.Cu" signal "IN5")
		(30 "In14.Cu" signal "GND6")
		(32 "In15.Cu" signal "IN6")
		(34 "In16.Cu" signal "GND7")
		(2 "B.Cu" signal "BOTTOM")
		(9 "F.Adhes" user "F.Adhesive")
		(11 "B.Adhes" user "B.Adhesive")
		(13 "F.Paste" user "Package Geometry/Pastemask Top")
		(15 "B.Paste" user "Package Geometry/Pastemask Bottom")
		(5 "F.SilkS" user "Ref Des/Silkscreen Top")
		(7 "B.SilkS" user "Ref Des/Silkscreen Bottom")
		(1 "F.Mask" user "Board Geometry/Soldermask Top")
		(3 "B.Mask" user "Board Geometry/Soldermask Bottom")
		(17 "Dwgs.User" user "User.Drawings")
		(19 "Cmts.User" user "User.Comments")
		(21 "Eco1.User" user "User.Eco1")
		(23 "Eco2.User" user "User.Eco2")
		(25 "Edge.Cuts" user "Board Geometry/Outline")
		(27 "Margin" user)
		(31 "F.CrtYd" user "Package Geometry/Place Bound Top")
		(29 "B.CrtYd" user "Package Geometry/Place Bound Bottom")
		(35 "F.Fab" user "Ref Des/Assembly Top")
		(33 "B.Fab" user "Ref Des/Assembly Bottom")
	)
	(footprint ""
		(layer "B.Cu")
		(at 110.856014 -259.845302 180)
		(property "Reference" "C2502"
			(at 0 0 0)
			(layer "B.SilkS")
			(hide yes)
			(effects
				(font
					(size 1.27 1.27)
				)
				(justify mirror)
			)
		)
		(property "Value" ""
			(at 0 0 0)
			(layer "B.Fab")
			(effects
				(font
					(size 1.27 1.27)
				)
				(justify mirror)
			)
		)
		(duplicate_pad_numbers_are_jumpers no)
		(fp_line
			(start 0.7874 0.4064)
			(end 0.7874 -0.4064)
			(stroke
				(width 0.1524)
				(type default)
			)
			(layer "B.SilkS")
		)
		(fp_line
			(start 0.7874 -0.4064)
			(end -0.7874 -0.4064)
			(stroke
				(width 0.1524)
				(type default)
			)
			(layer "B.SilkS")
		)
		(fp_line
			(start -0.7874 0.4064)
			(end 0.7874 0.4064)
			(stroke
				(width 0.1524)
				(type default)
			)
			(layer "B.SilkS")
		)
		(fp_line
			(start -0.7874 -0.4064)
			(end -0.7874 0.4064)
			(stroke
				(width 0.1524)
				(type default)
			)
			(layer "B.SilkS")
		)
		(fp_line
			(start 0.67945 0.3048)
			(end 0.67945 -0.305054)
			(stroke
				(width 0.1)
				(type default)
			)
			(layer "B.Fab")
		)
		(fp_line
			(start 0.67945 -0.305054)
			(end 0.12065 -0.305054)
			(stroke
				(width 0.1)
				(type default)
			)
			(layer "B.Fab")
		)
		(fp_line
			(start 0.12065 0.3048)
			(end 0.67945 0.3048)
			(stroke
				(width 0.1)
				(type default)
			)
			(layer "B.Fab")
		)
		(fp_line
			(start 0.12065 0.2794)
			(end 0.12065 0.3048)
			(stroke
				(width 0.1)
				(type default)
			)
			(layer "B.Fab")
		)
		(fp_line
			(start 0.12065 -0.2794)
			(end -0.12065 -0.2794)
			(stroke
				(width 0.1)
				(type default)
			)
			(layer "B.Fab")
		)
		(fp_line
			(start 0.12065 -0.305054)
			(end 0.12065 -0.2794)
			(stroke
				(width 0.1)
				(type default)
			)
			(layer "B.Fab")
		)
		(fp_line
			(start -0.120396 0.3048)
			(end -0.120396 0.2794)
			(stroke
				(width 0.1)
				(type default)
			)
			(layer "B.Fab")
		)
		(fp_line
			(start -0.120396 0.2794)
			(end 0.12065 0.2794)
			(stroke
				(width 0.1)
				(type default)
			)
			(layer "B.Fab")
		)
		(fp_line
			(start -0.12065 -0.2794)
			(end -0.12065 -0.3048)
			(stroke
				(width 0.1)
				(type default)
			)
			(layer "B.Fab")
		)
		(fp_line
			(start -0.12065 -0.3048)
			(end -0.67945 -0.3048)
			(stroke
				(width 0.1)
				(type default)
			)
			(layer "B.Fab")
		)
		(fp_line
			(start -0.67945 0.3048)
			(end -0.120396 0.3048)
			(stroke
				(width 0.1)
				(type default)
			)
			(layer "B.Fab")
		)
		(fp_line
			(start -0.67945 -0.3048)
			(end -0.67945 0.3048)
			(stroke
				(width 0.1)
				(type default)
			)
			(layer "B.Fab")
		)
		(pad "1" smd circle
			(at 0.40005 0)
			(size 0 0)
			(layers "B.Cu" "B.Mask" "B.Paste")
			(net "PVDD11_S3_P1")
		)
		(pad "2" smd circle
			(at -0.40005 0)
			(size 0 0)
			(layers "B.Cu" "B.Mask" "B.Paste")
			(net "GND")
		)
	)
	(footprint ""
		(layer "B.Cu")
		(at 358.037892 -416.91687 180)
		(property "Reference" "R2934"
			(at 0 0 0)
			(layer "B.SilkS")
			(hide yes)
			(effects
				(font
					(size 1.27 1.27)
				)
				(justify mirror)
			)
		)
		(property "Value" ""
			(at 0 0 0)
			(layer "B.Fab")
			(effects
				(font
					(size 1.27 1.27)
				)
				(justify mirror)
			)
		)
		(duplicate_pad_numbers_are_jumpers no)
		(fp_line
			(start 0.7874 0.4064)
			(end 0.7874 -0.4064)
			(stroke
				(width 0.1524)
				(type default)
			)
			(layer "B.SilkS")
		)
		(fp_line
			(start 0.7874 -0.4064)
			(end -0.7874 -0.4064)
			(stroke
				(width 0.1524)
				(type default)
			)
			(layer "B.SilkS")
		)
		(fp_line
			(start -0.7874 0.4064)
			(end 0.7874 0.4064)
			(stroke
				(width 0.1524)
				(type default)
			)
			(layer "B.SilkS")
		)
		(fp_line
			(start -0.7874 -0.4064)
			(end -0.7874 0.4064)
			(stroke
				(width 0.1524)
				(type default)
			)
			(layer "B.SilkS")
		)
		(fp_line
			(start 0.67945 0.3048)
			(end 0.67945 -0.305054)
			(stroke
				(width 0.1)
				(type default)
			)
			(layer "B.Fab")
		)
		(fp_line
			(start 0.67945 -0.305054)
			(end 0.12065 -0.305054)
			(stroke
				(width 0.1)
				(type default)
			)
			(layer "B.Fab")
		)
		(fp_line
			(start 0.12065 0.3048)
			(end 0.67945 0.3048)
			(stroke
				(width 0.1)
				(type default)
			)
			(layer "B.Fab")
		)
		(fp_line
			(start 0.12065 0.2794)
			(end 0.12065 0.3048)
			(stroke
				(width 0.1)
				(type default)
			)
			(layer "B.Fab")
		)
		(fp_line
			(start 0.12065 -0.2794)
			(end -0.12065 -0.2794)
			(stroke
				(width 0.1)
				(type default)
			)
			(layer "B.Fab")
		)
		(fp_line
			(start 0.12065 -0.305054)
			(end 0.12065 -0.2794)
			(stroke
				(width 0.1)
				(type default)
			)
			(layer "B.Fab")
		)
		(fp_line
			(start -0.120396 0.3048)
			(end -0.120396 0.2794)
			(stroke
				(width 0.1)
				(type default)
			)
			(layer "B.Fab")
		)
		(fp_line
			(start -0.120396 0.2794)
			(end 0.12065 0.2794)
			(stroke
				(width 0.1)
				(type default)
			)
			(layer "B.Fab")
		)
		(fp_line
			(start -0.12065 -0.2794)
			(end -0.12065 -0.3048)
			(stroke
				(width 0.1)
				(type default)
			)
			(layer "B.Fab")
		)
		(fp_line
			(start -0.12065 -0.3048)
			(end -0.67945 -0.3048)
			(stroke
				(width 0.1)
				(type default)
			)
			(layer "B.Fab")
		)
		(fp_line
			(start -0.67945 0.3048)
			(end -0.120396 0.3048)
			(stroke
				(width 0.1)
				(type default)
			)
			(layer "B.Fab")
		)
		(fp_line
			(start -0.67945 -0.3048)
			(end -0.67945 0.3048)
			(stroke
				(width 0.1)
				(type default)
			)
			(layer "B.Fab")
		)
		(pad "1" smd circle
			(at 0.40005 0)
			(size 0 0)
			(layers "B.Cu" "B.Mask" "B.Paste")
			(net "P3V3_AUX")
		)
		(pad "2" smd circle
			(at -0.40005 0)
			(size 0 0)
			(layers "B.Cu" "B.Mask" "B.Paste")
			(net "FM_SWB_PWRGD_ISO")
		)
	)
	(footprint ""
		(layer "B.Cu")
		(at 378.526802 -416.899344 90)
		(property "Reference" "C6602"
			(at 0 0 90)
			(layer "B.SilkS")
			(hide yes)
			(effects
				(font
					(size 1.27 1.27)
				)
				(justify mirror)
			)
		)
		(property "Value" ""
			(at 0 0 90)
			(layer "B.Fab")
			(effects
				(font
					(size 1.27 1.27)
				)
				(justify mirror)
			)
		)
		(duplicate_pad_numbers_are_jumpers no)
		(fp_line
			(start 0.299974 -0.150114)
			(end -0.299974 -0.150114)
			(stroke
				(width 0.1)
				(type default)
			)
			(layer "B.Fab")
		)
		(fp_line
			(start -0.299974 -0.150114)
			(end -0.299974 0.150114)
			(stroke
				(width 0.1)
				(type default)
			)
			(layer "B.Fab")
		)
		(fp_line
			(start 0.299974 0.150114)
			(end 0.299974 -0.150114)
			(stroke
				(width 0.1)
				(type default)
			)
			(layer "B.Fab")
		)
		(fp_line
			(start -0.299974 0.150114)
			(end 0.299974 0.150114)
			(stroke
				(width 0.1)
				(type default)
			)
			(layer "B.Fab")
		)
		(pad "1" smd rect
			(at 0.2667 0 270)
			(size 0.3048 0.381)
			(layers "B.Cu" "B.Mask" "B.Paste")
			(net "P5E_CPU0_P3_TX_BUF_C_DN<2>")
		)
		(pad "2" smd rect
			(at -0.2667 0 270)
			(size 0.3048 0.381)
			(layers "B.Cu" "B.Mask" "B.Paste")
			(net "P5E_CPU0_P3_TX_BUF_DN<2>")
		)
	)
	(footprint ""
		(layer "B.Cu")
		(at 214.884 -331.724)
		(property "Reference" "R6774"
			(at 0 0 0)
			(layer "B.SilkS")
			(hide yes)
			(effects
				(font
					(size 1.27 1.27)
				)
				(justify mirror)
			)
		)
		(property "Value" ""
			(at 0 0 0)
			(layer "B.Fab")
			(effects
				(font
					(size 1.27 1.27)
				)
				(justify mirror)
			)
		)
		(duplicate_pad_numbers_are_jumpers no)
		(fp_line
			(start -0.32512 -0.175006)
			(end -0.32512 0.175006)
			(stroke
				(width 0.1)
				(type default)
			)
			(layer "B.Fab")
		)
		(fp_line
			(start -0.32512 0.175006)
			(end 0.32512 0.175006)
			(stroke
				(width 0.1)
				(type default)
			)
			(layer "B.Fab")
		)
		(fp_line
			(start 0.32512 -0.175006)
			(end -0.32512 -0.175006)
			(stroke
				(width 0.1)
				(type default)
			)
			(layer "B.Fab")
		)
		(fp_line
			(start 0.32512 0.175006)
			(end 0.32512 -0.175006)
			(stroke
				(width 0.1)
				(type default)
			)
			(layer "B.Fab")
		)
		(pad "1" smd rect
			(at 0.2667 0 180)
			(size 0.3048 0.381)
			(layers "B.Cu" "B.Mask" "B.Paste")
			(net "RT_SMB_MUX_ADDR1")
		)
		(pad "2" smd rect
			(at -0.2667 0)
			(size 0.3048 0.381)
			(layers "B.Cu" "B.Mask" "B.Paste")
			(net "GND")
		)
	)
	(footprint ""
		(layer "B.Cu")
		(at 346.532454 -266.64031)
		(property "Reference" "C2515"
			(at 0 0 0)
			(layer "B.SilkS")
			(hide yes)
			(effects
				(font
					(size 1.27 1.27)
				)
				(justify mirror)
			)
		)
		(property "Value" ""
			(at 0 0 0)
			(layer "B.Fab")
			(effects
				(font
					(size 1.27 1.27)
				)
				(justify mirror)
			)
		)
		(duplicate_pad_numbers_are_jumpers no)
		(fp_line
			(start -0.7874 -0.4064)
			(end -0.7874 0.4064)
			(stroke
				(width 0.1524)
				(type default)
			)
			(layer "B.SilkS")
		)
		(fp_line
			(start -0.7874 0.4064)
			(end 0.7874 0.4064)
			(stroke
				(width 0.1524)
				(type default)
			)
			(layer "B.SilkS")
		)
		(fp_line
			(start 0.7874 -0.4064)
			(end -0.7874 -0.4064)
			(stroke
				(width 0.1524)
				(type default)
			)
			(layer "B.SilkS")
		)
		(fp_line
			(start 0.7874 0.4064)
			(end 0.7874 -0.4064)
			(stroke
				(width 0.1524)
				(type default)
			)
			(layer "B.SilkS")
		)
		(fp_line
			(start -0.67945 -0.3048)
			(end -0.67945 0.3048)
			(stroke
				(width 0.1)
				(type default)
			)
			(layer "B.Fab")
		)
		(fp_line
			(start -0.67945 0.3048)
			(end -0.120396 0.3048)
			(stroke
				(width 0.1)
				(type default)
			)
			(layer "B.Fab")
		)
		(fp_line
			(start -0.12065 -0.3048)
			(end -0.67945 -0.3048)
			(stroke
				(width 0.1)
				(type default)
			)
			(layer "B.Fab")
		)
		(fp_line
			(start -0.12065 -0.2794)
			(end -0.12065 -0.3048)
			(stroke
				(width 0.1)
				(type default)
			)
			(layer "B.Fab")
		)
		(fp_line
			(start -0.120396 0.2794)
			(end 0.12065 0.2794)
			(stroke
				(width 0.1)
				(type default)
			)
			(layer "B.Fab")
		)
		(fp_line
			(start -0.120396 0.3048)
			(end -0.120396 0.2794)
			(stroke
				(width 0.1)
				(type default)
			)
			(layer "B.Fab")
		)
		(fp_line
			(start 0.12065 -0.305054)
			(end 0.12065 -0.2794)
			(stroke
				(width 0.1)
				(type default)
			)
			(layer "B.Fab")
		)
		(fp_line
			(start 0.12065 -0.2794)
			(end -0.12065 -0.2794)
			(stroke
				(width 0.1)
				(type default)
			)
			(layer "B.Fab")
		)
		(fp_line
			(start 0.12065 0.2794)
			(end 0.12065 0.3048)
			(stroke
				(width 0.1)
				(type default)
			)
			(layer "B.Fab")
		)
		(fp_line
			(start 0.12065 0.3048)
			(end 0.67945 0.3048)
			(stroke
				(width 0.1)
				(type default)
			)
			(layer "B.Fab")
		)
		(fp_line
			(start 0.67945 -0.305054)
			(end 0.12065 -0.305054)
			(stroke
				(width 0.1)
				(type default)
			)
			(layer "B.Fab")
		)
		(fp_line
			(start 0.67945 0.3048)
			(end 0.67945 -0.305054)
			(stroke
				(width 0.1)
				(type default)
			)
			(layer "B.Fab")
		)
		(pad "1" smd circle
			(at 0.40005 0 180)
			(size 0 0)
			(layers "B.Cu" "B.Mask" "B.Paste")
			(net "PVDD_33_S5")
		)
		(pad "2" smd circle
			(at -0.40005 0 180)
			(size 0 0)
			(layers "B.Cu" "B.Mask" "B.Paste")
			(net "GND")
		)
	)
	(footprint ""
		(layer "B.Cu")
		(at 71.530718 -335.06791 90)
		(property "Reference" "PC416_3"
			(at 0 0 90)
			(layer "B.SilkS")
			(hide yes)
			(effects
				(font
					(size 1.27 1.27)
				)
				(justify mirror)
			)
		)
		(property "Value" ""
			(at 0 0 90)
			(layer "B.Fab")
			(effects
				(font
					(size 1.27 1.27)
				)
				(justify mirror)
			)
		)
		(duplicate_pad_numbers_are_jumpers no)
		(fp_line
			(start 1.524 -0.762)
			(end -1.524 -0.762)
			(stroke
				(width 0.1524)
				(type default)
			)
			(layer "B.SilkS")
		)
		(fp_line
			(start -1.524 -0.762)
			(end -1.524 0.762)
			(stroke
				(width 0.1524)
				(type default)
			)
			(layer "B.SilkS")
		)
		(fp_line
			(start 1.524 0.762)
			(end 1.524 -0.762)
			(stroke
				(width 0.1524)
				(type default)
			)
			(layer "B.SilkS")
		)
		(fp_line
			(start -1.524 0.762)
			(end 1.524 0.762)
			(stroke
				(width 0.1524)
				(type default)
			)
			(layer "B.SilkS")
		)
		(fp_line
			(start 1.1049 -0.724916)
			(end 1.1049 0.724916)
			(stroke
				(width 0.1)
				(type default)
			)
			(layer "B.Fab")
		)
		(fp_line
			(start -1.1049 -0.724916)
			(end 1.1049 -0.724916)
			(stroke
				(width 0.1)
				(type default)
			)
			(layer "B.Fab")
		)
		(fp_line
			(start 1.1049 0.724916)
			(end -1.1049 0.724916)
			(stroke
				(width 0.1)
				(type default)
			)
			(layer "B.Fab")
		)
		(fp_line
			(start -1.1049 0.724916)
			(end -1.1049 -0.724916)
			(stroke
				(width 0.1)
				(type default)
			)
			(layer "B.Fab")
		)
		(pad "1" smd rect
			(at 0.889 0 90)
			(size 1.016 1.27)
			(layers "B.Cu" "B.Mask" "B.Paste")
			(net "SW_P12V_AUX_PVDDCR_CPU1_P1_FLT")
		)
		(pad "2" smd rect
			(at -0.889 0 90)
			(size 1.016 1.27)
			(layers "B.Cu" "B.Mask" "B.Paste")
			(net "GND")
		)
	)
	(footprint ""
		(layer "B.Cu")
		(at 435.406292 -341.921846 -90)
		(property "Reference" "PC227_1"
			(at 0 0 90)
			(layer "B.SilkS")
			(hide yes)
			(effects
				(font
					(size 1.27 1.27)
				)
				(justify mirror)
			)
		)
		(property "Value" ""
			(at 0 0 90)
			(layer "B.Fab")
			(effects
				(font
					(size 1.27 1.27)
				)
				(justify mirror)
			)
		)
		(duplicate_pad_numbers_are_jumpers no)
		(fp_line
			(start -1.524 0.762)
			(end 1.524 0.762)
			(stroke
				(width 0.1524)
				(type default)
			)
			(layer "B.SilkS")
		)
		(fp_line
			(start 1.524 0.762)
			(end 1.524 -0.762)
			(stroke
				(width 0.1524)
				(type default)
			)
			(layer "B.SilkS")
		)
		(fp_line
			(start -1.524 -0.762)
			(end -1.524 0.762)
			(stroke
				(width 0.1524)
				(type default)
			)
			(layer "B.SilkS")
		)
		(fp_line
			(start 1.524 -0.762)
			(end -1.524 -0.762)
			(stroke
				(width 0.1524)
				(type default)
			)
			(layer "B.SilkS")
		)
		(fp_line
			(start -1.1049 0.724916)
			(end -1.1049 -0.724916)
			(stroke
				(width 0.1)
				(type default)
			)
			(layer "B.Fab")
		)
		(fp_line
			(start 1.1049 0.724916)
			(end -1.1049 0.724916)
			(stroke
				(width 0.1)
				(type default)
			)
			(layer "B.Fab")
		)
		(fp_line
			(start -1.1049 -0.724916)
			(end 1.1049 -0.724916)
			(stroke
				(width 0.1)
				(type default)
			)
			(layer "B.Fab")
		)
		(fp_line
			(start 1.1049 -0.724916)
			(end 1.1049 0.724916)
			(stroke
				(width 0.1)
				(type default)
			)
			(layer "B.Fab")
		)
		(pad "1" smd rect
			(at 0.889 0 270)
			(size 1.016 1.27)
			(layers "B.Cu" "B.Mask" "B.Paste")
			(net "PVDD11_S3_P0")
		)
		(pad "2" smd rect
			(at -0.889 0 270)
			(size 1.016 1.27)
			(layers "B.Cu" "B.Mask" "B.Paste")
			(net "GND")
		)
	)
	(footprint ""
		(layer "B.Cu")
		(at 29.722318 -346.788994 90)
		(property "Reference" "PC633_4"
			(at 0 0 90)
			(layer "B.SilkS")
			(hide yes)
			(effects
				(font
					(size 1.27 1.27)
				)
				(justify mirror)
			)
		)
		(property "Value" ""
			(at 0 0 90)
			(layer "B.Fab")
			(effects
				(font
					(size 1.27 1.27)
				)
				(justify mirror)
			)
		)
		(duplicate_pad_numbers_are_jumpers no)
		(fp_line
			(start 1.524 -0.762)
			(end -1.524 -0.762)
			(stroke
				(width 0.1524)
				(type default)
			)
			(layer "B.SilkS")
		)
		(fp_line
			(start -1.524 -0.762)
			(end -1.524 0.762)
			(stroke
				(width 0.1524)
				(type default)
			)
			(layer "B.SilkS")
		)
		(fp_line
			(start 1.524 0.762)
			(end 1.524 -0.762)
			(stroke
				(width 0.1524)
				(type default)
			)
			(layer "B.SilkS")
		)
		(fp_line
			(start -1.524 0.762)
			(end 1.524 0.762)
			(stroke
				(width 0.1524)
				(type default)
			)
			(layer "B.SilkS")
		)
		(fp_line
			(start 1.1049 -0.724916)
			(end 1.1049 0.724916)
			(stroke
				(width 0.1)
				(type default)
			)
			(layer "B.Fab")
		)
		(fp_line
			(start -1.1049 -0.724916)
			(end 1.1049 -0.724916)
			(stroke
				(width 0.1)
				(type default)
			)
			(layer "B.Fab")
		)
		(fp_line
			(start 1.1049 0.724916)
			(end -1.1049 0.724916)
			(stroke
				(width 0.1)
				(type default)
			)
			(layer "B.Fab")
		)
		(fp_line
			(start -1.1049 0.724916)
			(end -1.1049 -0.724916)
			(stroke
				(width 0.1)
				(type default)
			)
			(layer "B.Fab")
		)
		(pad "1" smd rect
			(at 0.889 0 90)
			(size 1.016 1.27)
			(layers "B.Cu" "B.Mask" "B.Paste")
			(net "SW_P12V_AUX_PVDDIO_P1_FLT")
		)
		(pad "2" smd rect
			(at -0.889 0 90)
			(size 1.016 1.27)
			(layers "B.Cu" "B.Mask" "B.Paste")
			(net "GND")
		)
	)
)
